# S9S_MB_2U (Grand Teton) — schematic netlist excerpt (pin names and nets, part order shuffled) for the footprints in the layout excerpt that follows; sources: Cadence DE-HDL packaged netlist, KiCad conversion of 03242023_DA0F0TMBIJ0_F0T_Motherboard_J_brd_V01_OCP.brd

R3043  Q_RES  33.2 1% CHIP  pkg 0402LF  page 213 : A = IRQ_HSC_FAULT_N ; B = IRQ_HSC_FAULT_R1_N

(kicad_pcb
	(version 20260206)
	(generator "pcbnew")
	(generator_version "10.0")
	(general
		(thickness 1.6)
		(legacy_teardrops no)
	)
	(paper "A4")
	(title_block
		(title "03242023_DA0F0TMBIJ0_F0T_Motherboard_J_brd_V01_OCP.brd")
		(comment 1 "Grand Teton / footprints 3598-3598 of 6105")
	)
	(layers
		(0 "F.Cu" signal "TOP")
		(4 "In1.Cu" signal "GND")
		(6 "In2.Cu" signal "IN1")
		(8 "In3.Cu" signal "GND1")
		(10 "In4.Cu" signal "IN2")
		(12 "In5.Cu" signal "GND2")
		(14 "In6.Cu" signal "IN3")
		(16 "In7.Cu" signal "GND3")
		(18 "In8.Cu" signal "VCC")
		(20 "In9.Cu" signal "VCC1")
		(22 "In10.Cu" signal "GND4")
		(24 "In11.Cu" signal "IN4")
		(26 "In12.Cu" signal "GND5")
		(28 "In13.Cu" signal "IN5")
		(30 "In14.Cu" signal "GND6")
		(32 "In15.Cu" signal "IN6")
		(34 "In16.Cu" signal "GND7")
		(2 "B.Cu" signal "BOTTOM")
		(9 "F.Adhes" user "F.Adhesive")
		(11 "B.Adhes" user "B.Adhesive")
		(13 "F.Paste" user "Package Geometry/Pastemask Top")
		(15 "B.Paste" user "Package Geometry/Pastemask Bottom")
		(5 "F.SilkS" user "Ref Des/Silkscreen Top")
		(7 "B.SilkS" user "Ref Des/Silkscreen Bottom")
		(1 "F.Mask" user "Board Geometry/Soldermask Top")
		(3 "B.Mask" user "Board Geometry/Soldermask Bottom")
		(17 "Dwgs.User" user "User.Drawings")
		(19 "Cmts.User" user "User.Comments")
		(21 "Eco1.User" user "User.Eco1")
		(23 "Eco2.User" user "User.Eco2")
		(25 "Edge.Cuts" user "Board Geometry/Outline")
		(27 "Margin" user)
		(31 "F.CrtYd" user "Package Geometry/Place Bound Top")
		(29 "B.CrtYd" user "Package Geometry/Place Bound Bottom")
		(35 "F.Fab" user "Ref Des/Assembly Top")
		(33 "B.Fab" user "Ref Des/Assembly Bottom")
	)
	(footprint ""
		(layer "F.Cu")
		(at 160.83788 -107.025948)
		(property "Reference" "R3043"
			(at 0 0 0)
			(layer "F.SilkS")
			(hide yes)
			(effects
				(font
					(size 1.27 1.27)
				)
			)
		)
		(property "Value" ""
			(at 0 0 0)
			(layer "F.Fab")
			(effects
				(font
					(size 1.27 1.27)
				)
			)
		)
		(duplicate_pad_numbers_are_jumpers no)
		(fp_line
			(start -0.7874 -0.4064)
			(end 0.7874 -0.4064)
			(stroke
				(width 0.1524)
				(type default)
			)
			(layer "F.SilkS")
		)
		(fp_line
			(start -0.7874 0.4064)
			(end -0.7874 -0.4064)
			(stroke
				(width 0.1524)
				(type default)
			)
			(layer "F.SilkS")
		)
		(fp_line
			(start 0.7874 -0.4064)
			(end 0.7874 0.4064)
			(stroke
				(width 0.1524)
				(type default)
			)
			(layer "F.SilkS")
		)
		(fp_line
			(start 0.7874 0.4064)
			(end -0.7874 0.4064)
			(stroke
				(width 0.1524)
				(type default)
			)
			(layer "F.SilkS")
		)
		(fp_line
			(start -0.67945 -0.305054)
			(end -0.12065 -0.305054)
			(stroke
				(width 0.1)
				(type default)
			)
			(layer "F.Fab")
		)
		(fp_line
			(start -0.67945 0.3048)
			(end -0.67945 -0.305054)
			(stroke
				(width 0.1)
				(type default)
			)
			(layer "F.Fab")
		)
		(fp_line
			(start -0.12065 -0.305054)
			(end -0.12065 -0.2794)
			(stroke
				(width 0.1)
				(type default)
			)
			(layer "F.Fab")
		)
		(fp_line
			(start -0.12065 -0.2794)
			(end 0.12065 -0.2794)
			(stroke
				(width 0.1)
				(type default)
			)
			(layer "F.Fab")
		)
		(fp_line
			(start -0.12065 0.2794)
			(end -0.12065 0.3048)
			(stroke
				(width 0.1)
				(type default)
			)
			(layer "F.Fab")
		)
		(fp_line
			(start -0.12065 0.3048)
			(end -0.67945 0.3048)
			(stroke
				(width 0.1)
				(type default)
			)
			(layer "F.Fab")
		)
		(fp_line
			(start 0.120396 0.2794)
			(end -0.12065 0.2794)
			(stroke
				(width 0.1)
				(type default)
			)
			(layer "F.Fab")
		)
		(fp_line
			(start 0.120396 0.3048)
			(end 0.120396 0.2794)
			(stroke
				(width 0.1)
				(type default)
			)
			(layer "F.Fab")
		)
		(fp_line
			(start 0.12065 -0.3048)
			(end 0.67945 -0.3048)
			(stroke
				(width 0.1)
				(type default)
			)
			(layer "F.Fab")
		)
		(fp_line
			(start 0.12065 -0.2794)
			(end 0.12065 -0.3048)
			(stroke
				(width 0.1)
				(type default)
			)
			(layer "F.Fab")
		)
		(fp_line
			(start 0.67945 -0.3048)
			(end 0.67945 0.3048)
			(stroke
				(width 0.1)
				(type default)
			)
			(layer "F.Fab")
		)
		(fp_line
			(start 0.67945 0.3048)
			(end 0.120396 0.3048)
			(stroke
				(width 0.1)
				(type default)
			)
			(layer "F.Fab")
		)
		(pad "1" smd circle
			(at -0.40005 0)
			(size 0 0)
			(layers "F.Cu" "F.Mask" "F.Paste")
			(net "IRQ_HSC_FAULT_N")
		)
		(pad "2" smd circle
			(at 0.40005 0)
			(size 0 0)
			(layers "F.Cu" "F.Mask" "F.Paste")
			(net "IRQ_HSC_FAULT_R1_N")
		)
	)
)
